FILE_TYPE=LIBRARY_PARTS;
TIME=' Created/Modified on Fri Jan 10 09:01:05 2003' ;
primitive 'SCONN10_C12536004';
  pin
    'IO1':
      PIN_NUMBER='(1)';
      PINUSE='UNSPEC';
      NO_LOAD_CHECK='BOTH';
      NO_IO_CHECK='BOTH';
      ALLOW_CONNECT='TRUE';
    'IO2':
      PIN_NUMBER='(2)';
      PINUSE='UNSPEC';
      NO_LOAD_CHECK='BOTH';
      NO_IO_CHECK='BOTH';
      ALLOW_CONNECT='TRUE';
    'IO3':
      PIN_NUMBER='(3)';
      PINUSE='UNSPEC';
      NO_LOAD_CHECK='BOTH';
      NO_IO_CHECK='BOTH';
      ALLOW_CONNECT='TRUE';
    'IO4':
      PIN_NUMBER='(4)';
      PINUSE='UNSPEC';
      NO_LOAD_CHECK='BOTH';
      NO_IO_CHECK='BOTH';
      ALLOW_CONNECT='TRUE';
    'IO5':
      PIN_NUMBER='(5)';
      PINUSE='UNSPEC';
      NO_LOAD_CHECK='BOTH';
      NO_IO_CHECK='BOTH';
      ALLOW_CONNECT='TRUE';
    'IO6':
      PIN_NUMBER='(6)';
      PINUSE='UNSPEC';
      NO_LOAD_CHECK='BOTH';
      NO_IO_CHECK='BOTH';
      ALLOW_CONNECT='TRUE';
    'IO7':
      PIN_NUMBER='(7)';
      PINUSE='UNSPEC';
      NO_LOAD_CHECK='BOTH';
      NO_IO_CHECK='BOTH';
      ALLOW_CONNECT='TRUE';
    'IO8':
      PIN_NUMBER='(8)';
      PINUSE='UNSPEC';
      NO_LOAD_CHECK='BOTH';
      NO_IO_CHECK='BOTH';
      ALLOW_CONNECT='TRUE';
    'IO9':
      PIN_NUMBER='(9)';
      PINUSE='UNSPEC';
      NO_LOAD_CHECK='BOTH';
      NO_IO_CHECK='BOTH';
      ALLOW_CONNECT='TRUE';
    'IO10':
      PIN_NUMBER='(10)';
      PINUSE='UNSPEC';
      NO_LOAD_CHECK='BOTH';
      NO_IO_CHECK='BOTH';
      ALLOW_CONNECT='TRUE';
  end_pin;
  body
    PART_NAME='SCONN10_C12536004';
    PHYS_DES_PREFIX='J';
  end_body;
end_primitive;
END.
